# T6G (Grand Teton) — schematic netlist excerpt (pin names and nets, part order shuffled) for the footprints in the layout excerpt that follows; sources: Cadence DE-HDL packaged netlist, KiCad conversion of 04192023_DAF0TMB3IC0_F0TG_MB_C_brd_V02_OCP.brd

C375  Q_CAP  1UF 4V 20% X6S  pkg 0201  page 345 : A = P1V8_CPU1_RT2_1A_1D ; B = GND
C775  Q_CAP  0.1UF 10V 10% X7S  pkg C0201  page 301 : A = P1V8_CPU0_RT2_1A_1D ; B = GND
C311  Q_CAP  0.1UF 10V 10% X7S  pkg C0201  page 334 : A = P0V9_CPU1_RT_2D ; B = GND
C1007  Q_CAP  0.1UF 10V 10% X7S  pkg C0201  page 312 : A = P0V9_CPU0_RT_2D ; B = GND
PC6583  Q_CAP  22UF 16V 20% X6S  pkg C0805  page 363 : A = SW_P12V_AUX_P0V9_RETIMER_CPU0_FLT ; B = GND

(kicad_pcb
	(version 20260206)
	(generator "pcbnew")
	(generator_version "10.0")
	(general
		(thickness 1.6)
		(legacy_teardrops no)
	)
	(paper "A4")
	(title_block
		(title "04192023_DAF0TMB3IC0_F0TG_MB_C_brd_V02_OCP.brd")
		(comment 1 "Grand Teton / footprints 6633-6637 of 8354")
	)
	(layers
		(0 "F.Cu" signal "TOP")
		(4 "In1.Cu" signal "GND")
		(6 "In2.Cu" signal "IN1")
		(8 "In3.Cu" signal "GND1")
		(10 "In4.Cu" signal "IN2")
		(12 "In5.Cu" signal "GND2")
		(14 "In6.Cu" signal "IN3")
		(16 "In7.Cu" signal "GND3")
		(18 "In8.Cu" signal "VCC")
		(20 "In9.Cu" signal "VCC1")
		(22 "In10.Cu" signal "GND4")
		(24 "In11.Cu" signal "IN4")
		(26 "In12.Cu" signal "GND5")
		(28 "In13.Cu" signal "IN5")
		(30 "In14.Cu" signal "GND6")
		(32 "In15.Cu" signal "IN6")
		(34 "In16.Cu" signal "GND7")
		(2 "B.Cu" signal "BOTTOM")
		(9 "F.Adhes" user "F.Adhesive")
		(11 "B.Adhes" user "B.Adhesive")
		(13 "F.Paste" user "Package Geometry/Pastemask Top")
		(15 "B.Paste" user "Package Geometry/Pastemask Bottom")
		(5 "F.SilkS" user "Ref Des/Silkscreen Top")
		(7 "B.SilkS" user "Ref Des/Silkscreen Bottom")
		(1 "F.Mask" user "Board Geometry/Soldermask Top")
		(3 "B.Mask" user "Board Geometry/Soldermask Bottom")
		(17 "Dwgs.User" user "User.Drawings")
		(19 "Cmts.User" user "User.Comments")
		(21 "Eco1.User" user "User.Eco1")
		(23 "Eco2.User" user "User.Eco2")
		(25 "Edge.Cuts" user "Board Geometry/Outline")
		(27 "Margin" user)
		(31 "F.CrtYd" user "Package Geometry/Place Bound Top")
		(29 "B.CrtYd" user "Package Geometry/Place Bound Bottom")
		(35 "F.Fab" user "Ref Des/Assembly Top")
		(33 "B.Fab" user "Ref Des/Assembly Bottom")
	)
	(footprint ""
		(layer "B.Cu")
		(at 413.946086 -396.393162 -90)
		(property "Reference" "C775"
			(at 0 0 90)
			(layer "B.SilkS")
			(hide yes)
			(effects
				(font
					(size 1.27 1.27)
				)
				(justify mirror)
			)
		)
		(property "Value" ""
			(at 0 0 90)
			(layer "B.Fab")
			(effects
				(font
					(size 1.27 1.27)
				)
				(justify mirror)
			)
		)
		(duplicate_pad_numbers_are_jumpers no)
		(fp_line
			(start -0.299974 0.150114)
			(end 0.299974 0.150114)
			(stroke
				(width 0.1)
				(type default)
			)
			(layer "B.Fab")
		)
		(fp_line
			(start 0.299974 0.150114)
			(end 0.299974 -0.150114)
			(stroke
				(width 0.1)
				(type default)
			)
			(layer "B.Fab")
		)
		(fp_line
			(start -0.299974 -0.150114)
			(end -0.299974 0.150114)
			(stroke
				(width 0.1)
				(type default)
			)
			(layer "B.Fab")
		)
		(fp_line
			(start 0.299974 -0.150114)
			(end -0.299974 -0.150114)
			(stroke
				(width 0.1)
				(type default)
			)
			(layer "B.Fab")
		)
		(pad "1" smd rect
			(at 0.2667 0 90)
			(size 0.3048 0.381)
			(layers "B.Cu" "B.Mask" "B.Paste")
			(net "P1V8_CPU0_RT2_1A_1D")
		)
		(pad "2" smd rect
			(at -0.2667 0 90)
			(size 0.3048 0.381)
			(layers "B.Cu" "B.Mask" "B.Paste")
			(net "GND")
		)
	)
	(footprint ""
		(layer "B.Cu")
		(at 157.806136 -386.766562 90)
		(property "Reference" "C375"
			(at 0 0 90)
			(layer "B.SilkS")
			(hide yes)
			(effects
				(font
					(size 1.27 1.27)
				)
				(justify mirror)
			)
		)
		(property "Value" ""
			(at 0 0 90)
			(layer "B.Fab")
			(effects
				(font
					(size 1.27 1.27)
				)
				(justify mirror)
			)
		)
		(duplicate_pad_numbers_are_jumpers no)
		(fp_line
			(start 0.299974 -0.150114)
			(end -0.299974 -0.150114)
			(stroke
				(width 0.1)
				(type default)
			)
			(layer "B.Fab")
		)
		(fp_line
			(start -0.299974 -0.150114)
			(end -0.299974 0.150114)
			(stroke
				(width 0.1)
				(type default)
			)
			(layer "B.Fab")
		)
		(fp_line
			(start 0.299974 0.150114)
			(end 0.299974 -0.150114)
			(stroke
				(width 0.1)
				(type default)
			)
			(layer "B.Fab")
		)
		(fp_line
			(start -0.299974 0.150114)
			(end 0.299974 0.150114)
			(stroke
				(width 0.1)
				(type default)
			)
			(layer "B.Fab")
		)
		(pad "1" smd rect
			(at 0.2667 0 270)
			(size 0.3048 0.381)
			(layers "B.Cu" "B.Mask" "B.Paste")
			(net "P1V8_CPU1_RT2_1A_1D")
		)
		(pad "2" smd rect
			(at -0.2667 0 270)
			(size 0.3048 0.381)
			(layers "B.Cu" "B.Mask" "B.Paste")
			(net "GND")
		)
	)
	(footprint ""
		(layer "B.Cu")
		(at 376.478546 -395.148562 90)
		(property "Reference" "C1007"
			(at 0 0 90)
			(layer "B.SilkS")
			(hide yes)
			(effects
				(font
					(size 1.27 1.27)
				)
				(justify mirror)
			)
		)
		(property "Value" ""
			(at 0 0 90)
			(layer "B.Fab")
			(effects
				(font
					(size 1.27 1.27)
				)
				(justify mirror)
			)
		)
		(duplicate_pad_numbers_are_jumpers no)
		(fp_line
			(start 0.299974 -0.150114)
			(end -0.299974 -0.150114)
			(stroke
				(width 0.1)
				(type default)
			)
			(layer "B.Fab")
		)
		(fp_line
			(start -0.299974 -0.150114)
			(end -0.299974 0.150114)
			(stroke
				(width 0.1)
				(type default)
			)
			(layer "B.Fab")
		)
		(fp_line
			(start 0.299974 0.150114)
			(end 0.299974 -0.150114)
			(stroke
				(width 0.1)
				(type default)
			)
			(layer "B.Fab")
		)
		(fp_line
			(start -0.299974 0.150114)
			(end 0.299974 0.150114)
			(stroke
				(width 0.1)
				(type default)
			)
			(layer "B.Fab")
		)
		(pad "1" smd rect
			(at 0.2667 0 270)
			(size 0.3048 0.381)
			(layers "B.Cu" "B.Mask" "B.Paste")
			(net "P0V9_CPU0_RT_2D")
		)
		(pad "2" smd rect
			(at -0.2667 0 270)
			(size 0.3048 0.381)
			(layers "B.Cu" "B.Mask" "B.Paste")
			(net "GND")
		)
	)
	(footprint ""
		(layer "B.Cu")
		(at 92.046298 -388.011162 -90)
		(property "Reference" "C311"
			(at 0 0 90)
			(layer "B.SilkS")
			(hide yes)
			(effects
				(font
					(size 1.27 1.27)
				)
				(justify mirror)
			)
		)
		(property "Value" ""
			(at 0 0 90)
			(layer "B.Fab")
			(effects
				(font
					(size 1.27 1.27)
				)
				(justify mirror)
			)
		)
		(duplicate_pad_numbers_are_jumpers no)
		(fp_line
			(start -0.299974 0.150114)
			(end 0.299974 0.150114)
			(stroke
				(width 0.1)
				(type default)
			)
			(layer "B.Fab")
		)
		(fp_line
			(start 0.299974 0.150114)
			(end 0.299974 -0.150114)
			(stroke
				(width 0.1)
				(type default)
			)
			(layer "B.Fab")
		)
		(fp_line
			(start -0.299974 -0.150114)
			(end -0.299974 0.150114)
			(stroke
				(width 0.1)
				(type default)
			)
			(layer "B.Fab")
		)
		(fp_line
			(start 0.299974 -0.150114)
			(end -0.299974 -0.150114)
			(stroke
				(width 0.1)
				(type default)
			)
			(layer "B.Fab")
		)
		(pad "1" smd rect
			(at 0.2667 0 90)
			(size 0.3048 0.381)
			(layers "B.Cu" "B.Mask" "B.Paste")
			(net "P0V9_CPU1_RT_2D")
		)
		(pad "2" smd rect
			(at -0.2667 0 90)
			(size 0.3048 0.381)
			(layers "B.Cu" "B.Mask" "B.Paste")
			(net "GND")
		)
	)
	(footprint ""
		(layer "B.Cu")
		(at 458.346302 -407.877264 180)
		(property "Reference" "PC6583"
			(at 0 0 0)
			(layer "B.SilkS")
			(hide yes)
			(effects
				(font
					(size 1.27 1.27)
				)
				(justify mirror)
			)
		)
		(property "Value" ""
			(at 0 0 0)
			(layer "B.Fab")
			(effects
				(font
					(size 1.27 1.27)
				)
				(justify mirror)
			)
		)
		(duplicate_pad_numbers_are_jumpers no)
		(fp_line
			(start 1.524 0.762)
			(end 1.524 -0.762)
			(stroke
				(width 0.1524)
				(type default)
			)
			(layer "B.SilkS")
		)
		(fp_line
			(start 1.524 -0.762)
			(end -1.524 -0.762)
			(stroke
				(width 0.1524)
				(type default)
			)
			(layer "B.SilkS")
		)
		(fp_line
			(start -1.524 0.762)
			(end 1.524 0.762)
			(stroke
				(width 0.1524)
				(type default)
			)
			(layer "B.SilkS")
		)
		(fp_line
			(start -1.524 -0.762)
			(end -1.524 0.762)
			(stroke
				(width 0.1524)
				(type default)
			)
			(layer "B.SilkS")
		)
		(fp_line
			(start 1.1049 0.724916)
			(end -1.1049 0.724916)
			(stroke
				(width 0.1)
				(type default)
			)
			(layer "B.Fab")
		)
		(fp_line
			(start 1.1049 -0.724916)
			(end 1.1049 0.724916)
			(stroke
				(width 0.1)
				(type default)
			)
			(layer "B.Fab")
		)
		(fp_line
			(start -1.1049 0.724916)
			(end -1.1049 -0.724916)
			(stroke
				(width 0.1)
				(type default)
			)
			(layer "B.Fab")
		)
		(fp_line
			(start -1.1049 -0.724916)
			(end 1.1049 -0.724916)
			(stroke
				(width 0.1)
				(type default)
			)
			(layer "B.Fab")
		)
		(pad "1" smd rect
			(at 0.889 0 180)
			(size 1.016 1.27)
			(layers "B.Cu" "B.Mask" "B.Paste")
			(net "SW_P12V_AUX_P0V9_RETIMER_CPU0_FLT")
		)
		(pad "2" smd rect
			(at -0.889 0 180)
			(size 1.016 1.27)
			(layers "B.Cu" "B.Mask" "B.Paste")
			(net "GND")
		)
	)
)
